# T6G (Grand Teton) — schematic netlist excerpt (pin names and nets, part order shuffled) for the footprints in the layout excerpt that follows; sources: Cadence DE-HDL packaged netlist, KiCad conversion of 04192023_DAF0TMB3IC0_F0TG_MB_C_brd_V02_OCP.brd

U245  NC7SB3157  NC7SB3157P6X EMPTY  pkg SMLF  page 143
  B1  = OCP_V3_2_NOT_PRSNT_RBT_ARB_IN
  GND  = GND
  B0  = OCP_V3_2_RBT_ARB_IN
  A  = OCP_SFF_RBT_ARB_IN_MUX2_R
  VCC  = P3V3_AUX
  S  = OCP_V3_2_PRSNT_ALL_R3_N

R9044  Q_RES  4.7K 1% EMPTY  pkg 0402LF  page 126 : A = P3V3_AUX ; B = GPU_WP_HW_CTRL_ISO_N

(kicad_pcb
	(version 20260206)
	(generator "pcbnew")
	(generator_version "10.0")
	(general
		(thickness 1.6)
		(legacy_teardrops no)
	)
	(paper "A4")
	(title_block
		(title "04192023_DAF0TMB3IC0_F0TG_MB_C_brd_V02_OCP.brd")
		(comment 1 "Grand Teton / footprints 3970-3971 of 8354")
	)
	(layers
		(0 "F.Cu" signal "TOP")
		(4 "In1.Cu" signal "GND")
		(6 "In2.Cu" signal "IN1")
		(8 "In3.Cu" signal "GND1")
		(10 "In4.Cu" signal "IN2")
		(12 "In5.Cu" signal "GND2")
		(14 "In6.Cu" signal "IN3")
		(16 "In7.Cu" signal "GND3")
		(18 "In8.Cu" signal "VCC")
		(20 "In9.Cu" signal "VCC1")
		(22 "In10.Cu" signal "GND4")
		(24 "In11.Cu" signal "IN4")
		(26 "In12.Cu" signal "GND5")
		(28 "In13.Cu" signal "IN5")
		(30 "In14.Cu" signal "GND6")
		(32 "In15.Cu" signal "IN6")
		(34 "In16.Cu" signal "GND7")
		(2 "B.Cu" signal "BOTTOM")
		(9 "F.Adhes" user "F.Adhesive")
		(11 "B.Adhes" user "B.Adhesive")
		(13 "F.Paste" user "Package Geometry/Pastemask Top")
		(15 "B.Paste" user "Package Geometry/Pastemask Bottom")
		(5 "F.SilkS" user "Ref Des/Silkscreen Top")
		(7 "B.SilkS" user "Ref Des/Silkscreen Bottom")
		(1 "F.Mask" user "Board Geometry/Soldermask Top")
		(3 "B.Mask" user "Board Geometry/Soldermask Bottom")
		(17 "Dwgs.User" user "User.Drawings")
		(19 "Cmts.User" user "User.Comments")
		(21 "Eco1.User" user "User.Eco1")
		(23 "Eco2.User" user "User.Eco2")
		(25 "Edge.Cuts" user "Board Geometry/Outline")
		(27 "Margin" user)
		(31 "F.CrtYd" user "Package Geometry/Place Bound Top")
		(29 "B.CrtYd" user "Package Geometry/Place Bound Bottom")
		(35 "F.Fab" user "Ref Des/Assembly Top")
		(33 "B.Fab" user "Ref Des/Assembly Bottom")
	)
	(footprint ""
		(layer "F.Cu")
		(at 144.74063 -95.612458)
		(property "Reference" "U245"
			(at -0.08128 1.90119 0)
			(unlocked yes)
			(layer "F.SilkS")
			(effects
				(font
					(size 0.7874 0.5842)
					(thickness 0.1524)
				)
			)
		)
		(property "Value" ""
			(at 0 0 0)
			(layer "F.Fab")
			(effects
				(font
					(size 1.27 1.27)
				)
			)
		)
		(duplicate_pad_numbers_are_jumpers no)
		(fp_line
			(start -1.7272 1.1176)
			(end -1.7272 -1.1176)
			(stroke
				(width 0.1524)
				(type default)
			)
			(layer "F.SilkS")
		)
		(fp_line
			(start -0.254 -1.1176)
			(end -1.7272 -1.1176)
			(stroke
				(width 0.1524)
				(type default)
			)
			(layer "F.SilkS")
		)
		(fp_line
			(start 0 -0.7366)
			(end -0.254 -1.1176)
			(stroke
				(width 0.1524)
				(type default)
			)
			(layer "F.SilkS")
		)
		(fp_line
			(start 0.254 -1.1176)
			(end 0 -0.7366)
			(stroke
				(width 0.1524)
				(type default)
			)
			(layer "F.SilkS")
		)
		(fp_line
			(start 1.7272 -1.1176)
			(end 0.254 -1.1176)
			(stroke
				(width 0.1524)
				(type default)
			)
			(layer "F.SilkS")
		)
		(fp_line
			(start 1.7272 -1.1176)
			(end 1.7272 1.1176)
			(stroke
				(width 0.1524)
				(type default)
			)
			(layer "F.SilkS")
		)
		(fp_line
			(start 1.7272 1.1176)
			(end -1.7272 1.1176)
			(stroke
				(width 0.1524)
				(type default)
			)
			(layer "F.SilkS")
		)
		(fp_poly
			(pts
				(xy -2.7178 -1.030986) (xy -1.9558 -0.649986) (xy -2.7178 -0.268986)
			)
			(stroke
				(width 0)
				(type default)
			)
			(fill yes)
			(layer "F.SilkS")
		)
		(fp_line
			(start -1.5748 -1.1176)
			(end -1.5748 1.1176)
			(stroke
				(width 0.1)
				(type default)
			)
			(layer "F.Fab")
		)
		(fp_line
			(start -1.5748 1.1176)
			(end 1.5748 1.1176)
			(stroke
				(width 0.1)
				(type default)
			)
			(layer "F.Fab")
		)
		(fp_line
			(start 1.5748 -1.1176)
			(end -1.5748 -1.1176)
			(stroke
				(width 0.1)
				(type default)
			)
			(layer "F.Fab")
		)
		(fp_line
			(start 1.5748 1.1176)
			(end 1.5748 -1.1176)
			(stroke
				(width 0.1)
				(type default)
			)
			(layer "F.Fab")
		)
		(fp_poly
			(pts
				(xy -1.9558 -0.649986) (xy -2.7178 -0.268986) (xy -2.7178 -1.030986)
			)
			(stroke
				(width 0)
				(type default)
			)
			(fill yes)
			(layer "F.Fab")
		)
		(pad "1" smd rect
			(at -0.999998 -0.649986 270)
			(size 0.3556 1.1176)
			(layers "F.Cu" "F.Mask" "F.Paste")
			(net "OCP_V3_2_NOT_PRSNT_RBT_ARB_IN")
		)
		(pad "2" smd rect
			(at -0.999998 0 270)
			(size 0.3556 1.1176)
			(layers "F.Cu" "F.Mask" "F.Paste")
			(net "GND")
		)
		(pad "3" smd rect
			(at -0.999998 0.649986 270)
			(size 0.3556 1.1176)
			(layers "F.Cu" "F.Mask" "F.Paste")
			(net "OCP_V3_2_RBT_ARB_IN")
		)
		(pad "4" smd rect
			(at 0.999998 0.649986 270)
			(size 0.3556 1.1176)
			(layers "F.Cu" "F.Mask" "F.Paste")
			(net "OCP_SFF_RBT_ARB_IN_MUX2_R")
		)
		(pad "5" smd rect
			(at 0.999998 0 270)
			(size 0.3556 1.1176)
			(layers "F.Cu" "F.Mask" "F.Paste")
			(net "P3V3_AUX")
		)
		(pad "6" smd rect
			(at 0.999998 -0.649986 270)
			(size 0.3556 1.1176)
			(layers "F.Cu" "F.Mask" "F.Paste")
			(net "OCP_V3_2_PRSNT_ALL_R3_N")
		)
	)
	(footprint ""
		(layer "F.Cu")
		(at 438.056782 -433.49926 90)
		(property "Reference" "R9044"
			(at 0 0 90)
			(layer "F.SilkS")
			(hide yes)
			(effects
				(font
					(size 1.27 1.27)
				)
			)
		)
		(property "Value" ""
			(at 0 0 90)
			(layer "F.Fab")
			(effects
				(font
					(size 1.27 1.27)
				)
			)
		)
		(duplicate_pad_numbers_are_jumpers no)
		(fp_line
			(start 0.7874 -0.4064)
			(end 0.7874 0.4064)
			(stroke
				(width 0.1524)
				(type default)
			)
			(layer "F.SilkS")
		)
		(fp_line
			(start -0.7874 -0.4064)
			(end 0.7874 -0.4064)
			(stroke
				(width 0.1524)
				(type default)
			)
			(layer "F.SilkS")
		)
		(fp_line
			(start 0.7874 0.4064)
			(end -0.7874 0.4064)
			(stroke
				(width 0.1524)
				(type default)
			)
			(layer "F.SilkS")
		)
		(fp_line
			(start -0.7874 0.4064)
			(end -0.7874 -0.4064)
			(stroke
				(width 0.1524)
				(type default)
			)
			(layer "F.SilkS")
		)
		(fp_line
			(start -0.12065 -0.305054)
			(end -0.12065 -0.2794)
			(stroke
				(width 0.1)
				(type default)
			)
			(layer "F.Fab")
		)
		(fp_line
			(start -0.67945 -0.305054)
			(end -0.12065 -0.305054)
			(stroke
				(width 0.1)
				(type default)
			)
			(layer "F.Fab")
		)
		(fp_line
			(start 0.67945 -0.3048)
			(end 0.67945 0.3048)
			(stroke
				(width 0.1)
				(type default)
			)
			(layer "F.Fab")
		)
		(fp_line
			(start 0.12065 -0.3048)
			(end 0.67945 -0.3048)
			(stroke
				(width 0.1)
				(type default)
			)
			(layer "F.Fab")
		)
		(fp_line
			(start 0.12065 -0.2794)
			(end 0.12065 -0.3048)
			(stroke
				(width 0.1)
				(type default)
			)
			(layer "F.Fab")
		)
		(fp_line
			(start -0.12065 -0.2794)
			(end 0.12065 -0.2794)
			(stroke
				(width 0.1)
				(type default)
			)
			(layer "F.Fab")
		)
		(fp_line
			(start 0.120396 0.2794)
			(end -0.12065 0.2794)
			(stroke
				(width 0.1)
				(type default)
			)
			(layer "F.Fab")
		)
		(fp_line
			(start -0.12065 0.2794)
			(end -0.12065 0.3048)
			(stroke
				(width 0.1)
				(type default)
			)
			(layer "F.Fab")
		)
		(fp_line
			(start 0.67945 0.3048)
			(end 0.120396 0.3048)
			(stroke
				(width 0.1)
				(type default)
			)
			(layer "F.Fab")
		)
		(fp_line
			(start 0.120396 0.3048)
			(end 0.120396 0.2794)
			(stroke
				(width 0.1)
				(type default)
			)
			(layer "F.Fab")
		)
		(fp_line
			(start -0.12065 0.3048)
			(end -0.67945 0.3048)
			(stroke
				(width 0.1)
				(type default)
			)
			(layer "F.Fab")
		)
		(fp_line
			(start -0.67945 0.3048)
			(end -0.67945 -0.305054)
			(stroke
				(width 0.1)
				(type default)
			)
			(layer "F.Fab")
		)
		(pad "1" smd circle
			(at -0.40005 0 90)
			(size 0 0)
			(layers "F.Cu" "F.Mask" "F.Paste")
			(net "P3V3_AUX")
		)
		(pad "2" smd circle
			(at 0.40005 0 90)
			(size 0 0)
			(layers "F.Cu" "F.Mask" "F.Paste")
			(net "GPU_WP_HW_CTRL_ISO_N")
		)
	)
)
